# BASEBOARD_FAB2 (Tioga Pass) — schematic netlist excerpt (pin names and nets, part order shuffled) for the footprints in the layout excerpt that follows; sources: Cadence DE-HDL packaged netlist, KiCad conversion of Wiwynn_Tioga_Pass_MB.brd

C6U9  CAP_A  0.01UF 25V 10% X7R  pkg 0402V  page 46 : A = M_B_VREF ; B = GND
R4T1  RES  0.0 5% CHIP  pkg 0402  page 89 : A = FM_ADR_COMPLETE_DLY ; B = FM_ADR_COMPLETE_R
C6M2  CAP_A  0.01UF 25V 10% X7R  pkg 0402V  page 98 : A = M_D_CPU_VREF ; B = GND

(kicad_pcb
	(version 20260206)
	(generator "pcbnew")
	(generator_version "10.0")
	(general
		(thickness 1.6)
		(legacy_teardrops no)
	)
	(paper "A4")
	(title_block
		(title "Wiwynn_Tioga_Pass_MB.brd")
		(comment 1 "Tioga Pass / footprints 3718-3720 of 4770")
	)
	(layers
		(0 "F.Cu" signal "TOP")
		(4 "In1.Cu" signal "L2GND")
		(6 "In2.Cu" signal "L3")
		(8 "In3.Cu" signal "L4GND")
		(10 "In4.Cu" signal "L5")
		(12 "In5.Cu" signal "L6GND")
		(14 "In6.Cu" signal "L7VCC")
		(16 "In7.Cu" signal "L8VCC")
		(18 "In8.Cu" signal "L9GND")
		(20 "In9.Cu" signal "L10")
		(22 "In10.Cu" signal "L11GND")
		(24 "In11.Cu" signal "L12")
		(26 "In12.Cu" signal "L13GND")
		(2 "B.Cu" signal "BOTTOM")
		(9 "F.Adhes" user "F.Adhesive")
		(11 "B.Adhes" user "B.Adhesive")
		(13 "F.Paste" user "Package Geometry/Pastemask Top")
		(15 "B.Paste" user "Package Geometry/Pastemask Bottom")
		(5 "F.SilkS" user "Ref Des/Silkscreen Top")
		(7 "B.SilkS" user "Ref Des/Silkscreen Bottom")
		(1 "F.Mask" user "Board Geometry/Soldermask Top")
		(3 "B.Mask" user "Board Geometry/Soldermask Bottom")
		(17 "Dwgs.User" user "User.Drawings")
		(19 "Cmts.User" user "User.Comments")
		(21 "Eco1.User" user "User.Eco1")
		(23 "Eco2.User" user "User.Eco2")
		(25 "Edge.Cuts" user "Board Geometry/Outline")
		(27 "Margin" user)
		(31 "F.CrtYd" user "Package Geometry/Place Bound Top")
		(29 "B.CrtYd" user "Package Geometry/Place Bound Bottom")
		(35 "F.Fab" user "Ref Des/Assembly Top")
		(33 "B.Fab" user "Ref Des/Assembly Bottom")
	)
	(footprint ""
		(layer "B.Cu")
		(at 318.9732 -34.2138 -90)
		(property "Reference" "R4T1"
			(at 0 0 90)
			(layer "B.SilkS")
			(hide yes)
			(effects
				(font
					(size 1.27 1.27)
				)
				(justify mirror)
			)
		)
		(property "Value" ""
			(at 0 0 90)
			(layer "B.Fab")
			(effects
				(font
					(size 1.27 1.27)
				)
				(justify mirror)
			)
		)
		(duplicate_pad_numbers_are_jumpers no)
		(fp_poly
			(pts
				(xy 0.2794 -0.1016) (xy -0.2794 -0.1016) (xy -0.2794 0.9906) (xy 0.2794 0.9906)
			)
			(stroke
				(width 0)
				(type default)
			)
			(fill no)
			(layer "B.CrtYd")
		)
		(fp_line
			(start -0.2794 0.9906)
			(end -0.2794 -0.1016)
			(stroke
				(width 0.1)
				(type default)
			)
			(layer "B.Fab")
		)
		(fp_line
			(start 0.2794 0.9906)
			(end -0.2794 0.9906)
			(stroke
				(width 0.1)
				(type default)
			)
			(layer "B.Fab")
		)
		(fp_line
			(start -0.2794 -0.1016)
			(end 0.2794 -0.1016)
			(stroke
				(width 0.1)
				(type default)
			)
			(layer "B.Fab")
		)
		(fp_line
			(start 0.2794 -0.1016)
			(end 0.2794 0.9906)
			(stroke
				(width 0.1)
				(type default)
			)
			(layer "B.Fab")
		)
		(pad "1" smd rect
			(at 0 0 90)
			(size 0.508 0.508)
			(layers "B.Cu" "B.Mask" "B.Paste")
			(net "FM_ADR_COMPLETE_DLY")
		)
		(pad "2" smd rect
			(at 0 0.889 90)
			(size 0.508 0.508)
			(layers "B.Cu" "B.Mask" "B.Paste")
			(net "FM_ADR_COMPLETE_R")
		)
		(zone
			(layer "B.Cu")
			(hatch none 0.5)
			(connect_pads
				(clearance 0)
			)
			(min_thickness 0.25)
			(keepout
				(tracks not_allowed)
				(vias allowed)
				(pads allowed)
				(copperpour not_allowed)
				(footprints allowed)
			)
			(placement
				(enabled no)
				(sheetname "")
			)
			(fill
				(thermal_gap 0.5)
				(thermal_bridge_width 0.5)
				(island_removal_mode 0)
			)
			(polygon
				(pts
					(xy 318.3382 -33.9598) (xy 318.3382 -34.4678) (xy 318.7192 -34.4678) (xy 318.7192 -33.9598)
				)
			)
		)
		(zone
			(layer "B.Cu")
			(hatch none 0.5)
			(connect_pads
				(clearance 0)
			)
			(min_thickness 0.25)
			(keepout
				(tracks allowed)
				(vias not_allowed)
				(pads allowed)
				(copperpour not_allowed)
				(footprints allowed)
			)
			(placement
				(enabled no)
				(sheetname "")
			)
			(fill
				(thermal_gap 0.5)
				(thermal_bridge_width 0.5)
				(island_removal_mode 0)
			)
			(polygon
				(pts
					(xy 318.7192 -33.9598) (xy 318.7192 -34.4678) (xy 318.3382 -34.4678) (xy 318.3382 -33.9598)
				)
			)
		)
	)
	(footprint ""
		(layer "B.Cu")
		(at 195.453 -8.122412 90)
		(property "Reference" "C6U9"
			(at 0 0 90)
			(layer "B.SilkS")
			(hide yes)
			(effects
				(font
					(size 1.27 1.27)
				)
				(justify mirror)
			)
		)
		(property "Value" ""
			(at 0 0 90)
			(layer "B.Fab")
			(effects
				(font
					(size 1.27 1.27)
				)
				(justify mirror)
			)
		)
		(duplicate_pad_numbers_are_jumpers no)
		(fp_poly
			(pts
				(xy -0.3048 -0.1016) (xy -0.3048 0.9906) (xy 0.3048 0.9906) (xy 0.3048 -0.1016)
			)
			(stroke
				(width 0)
				(type default)
			)
			(fill no)
			(layer "B.CrtYd")
		)
		(fp_line
			(start 0.3048 -0.1016)
			(end 0.3048 0.9906)
			(stroke
				(width 0.1)
				(type default)
			)
			(layer "B.Fab")
		)
		(fp_line
			(start -0.3048 -0.1016)
			(end 0.3048 -0.1016)
			(stroke
				(width 0.1)
				(type default)
			)
			(layer "B.Fab")
		)
		(fp_line
			(start 0.3048 0.9906)
			(end -0.3048 0.9906)
			(stroke
				(width 0.1)
				(type default)
			)
			(layer "B.Fab")
		)
		(fp_line
			(start -0.3048 0.9906)
			(end -0.3048 -0.1016)
			(stroke
				(width 0.1)
				(type default)
			)
			(layer "B.Fab")
		)
		(pad "1" smd rect
			(at 0 0 270)
			(size 0.508 0.508)
			(layers "B.Cu" "B.Mask" "B.Paste")
			(net "M_B_VREF")
		)
		(pad "2" smd rect
			(at 0 0.889 270)
			(size 0.508 0.508)
			(layers "B.Cu" "B.Mask" "B.Paste")
			(net "GND")
		)
		(zone
			(layer "B.Cu")
			(hatch none 0.5)
			(connect_pads
				(clearance 0)
			)
			(min_thickness 0.25)
			(keepout
				(tracks allowed)
				(vias not_allowed)
				(pads allowed)
				(copperpour not_allowed)
				(footprints allowed)
			)
			(placement
				(enabled no)
				(sheetname "")
			)
			(fill
				(thermal_gap 0.5)
				(thermal_bridge_width 0.5)
				(island_removal_mode 0)
			)
			(polygon
				(pts
					(xy 195.707 -8.376412) (xy 195.707 -7.868412) (xy 196.088 -7.868412) (xy 196.088 -8.376412)
				)
			)
		)
		(zone
			(layer "B.Cu")
			(hatch none 0.5)
			(connect_pads
				(clearance 0)
			)
			(min_thickness 0.25)
			(keepout
				(tracks not_allowed)
				(vias allowed)
				(pads allowed)
				(copperpour not_allowed)
				(footprints allowed)
			)
			(placement
				(enabled no)
				(sheetname "")
			)
			(fill
				(thermal_gap 0.5)
				(thermal_bridge_width 0.5)
				(island_removal_mode 0)
			)
			(polygon
				(pts
					(xy 196.088 -8.376412) (xy 196.088 -7.868412) (xy 195.707 -7.868412) (xy 195.707 -8.376412)
				)
			)
		)
	)
	(footprint ""
		(layer "B.Cu")
		(at 192.024 -134.874 180)
		(property "Reference" "C6M2"
			(at 0 0 0)
			(layer "B.SilkS")
			(hide yes)
			(effects
				(font
					(size 1.27 1.27)
				)
				(justify mirror)
			)
		)
		(property "Value" ""
			(at 0 0 0)
			(layer "B.Fab")
			(effects
				(font
					(size 1.27 1.27)
				)
				(justify mirror)
			)
		)
		(duplicate_pad_numbers_are_jumpers no)
		(fp_poly
			(pts
				(xy -0.3048 -0.1016) (xy -0.3048 0.9906) (xy 0.3048 0.9906) (xy 0.3048 -0.1016)
			)
			(stroke
				(width 0)
				(type default)
			)
			(fill no)
			(layer "B.CrtYd")
		)
		(fp_line
			(start 0.3048 0.9906)
			(end -0.3048 0.9906)
			(stroke
				(width 0.1)
				(type default)
			)
			(layer "B.Fab")
		)
		(fp_line
			(start 0.3048 -0.1016)
			(end 0.3048 0.9906)
			(stroke
				(width 0.1)
				(type default)
			)
			(layer "B.Fab")
		)
		(fp_line
			(start -0.3048 0.9906)
			(end -0.3048 -0.1016)
			(stroke
				(width 0.1)
				(type default)
			)
			(layer "B.Fab")
		)
		(fp_line
			(start -0.3048 -0.1016)
			(end 0.3048 -0.1016)
			(stroke
				(width 0.1)
				(type default)
			)
			(layer "B.Fab")
		)
		(pad "1" smd rect
			(at 0 0)
			(size 0.508 0.508)
			(layers "B.Cu" "B.Mask" "B.Paste")
			(net "M_D_CPU_VREF")
		)
		(pad "2" smd rect
			(at 0 0.889)
			(size 0.508 0.508)
			(layers "B.Cu" "B.Mask" "B.Paste")
			(net "GND")
		)
		(zone
			(layer "B.Cu")
			(hatch none 0.5)
			(connect_pads
				(clearance 0)
			)
			(min_thickness 0.25)
			(keepout
				(tracks not_allowed)
				(vias allowed)
				(pads allowed)
				(copperpour not_allowed)
				(footprints allowed)
			)
			(placement
				(enabled no)
				(sheetname "")
			)
			(fill
				(thermal_gap 0.5)
				(thermal_bridge_width 0.5)
				(island_removal_mode 0)
			)
			(polygon
				(pts
					(xy 191.77 -135.509) (xy 192.278 -135.509) (xy 192.278 -135.128) (xy 191.77 -135.128)
				)
			)
		)
		(zone
			(layer "B.Cu")
			(hatch none 0.5)
			(connect_pads
				(clearance 0)
			)
			(min_thickness 0.25)
			(keepout
				(tracks allowed)
				(vias not_allowed)
				(pads allowed)
				(copperpour not_allowed)
				(footprints allowed)
			)
			(placement
				(enabled no)
				(sheetname "")
			)
			(fill
				(thermal_gap 0.5)
				(thermal_bridge_width 0.5)
				(island_removal_mode 0)
			)
			(polygon
				(pts
					(xy 191.77 -135.128) (xy 192.278 -135.128) (xy 192.278 -135.509) (xy 191.77 -135.509)
				)
			)
		)
	)
)
